(kicad_pcb
	(version 20260206)
	(generator "pcbnew")
	(generator_version "10.0")
	(general
		(thickness 1.6)
		(legacy_teardrops no)
	)
	(paper "A4")
	(title_block
		(title "v1-pdb — T6M_PDB_D_0927_0900.brd")
		(comment 1 "Open CloudServer (Microsoft) / footprint 271 of 321 (J25), pads 1-78 of 166")
	)
	(layers
		(0 "F.Cu" signal "TOP")
		(4 "In1.Cu" signal "GND")
		(6 "In2.Cu" signal "IN1")
		(8 "In3.Cu" signal "VCC")
		(10 "In4.Cu" signal "VCC1")
		(12 "In5.Cu" signal "IN2")
		(14 "In6.Cu" signal "GND1")
		(2 "B.Cu" signal "BOTTOM")
		(9 "F.Adhes" user "F.Adhesive")
		(11 "B.Adhes" user "B.Adhesive")
		(13 "F.Paste" user "Package Geometry/Pastemask Top")
		(15 "B.Paste" user "Package Geometry/Pastemask Bottom")
		(5 "F.SilkS" user "Ref Des/Silkscreen Top")
		(7 "B.SilkS" user "Ref Des/Silkscreen Bottom")
		(1 "F.Mask" user "Board Geometry/Soldermask Top")
		(3 "B.Mask" user "Board Geometry/Soldermask Bottom")
		(17 "Dwgs.User" user "User.Drawings")
		(19 "Cmts.User" user "User.Comments")
		(21 "Eco1.User" user "User.Eco1")
		(23 "Eco2.User" user "User.Eco2")
		(25 "Edge.Cuts" user "Board Geometry/Outline")
		(27 "Margin" user)
		(31 "F.CrtYd" user "Package Geometry/Place Bound Top")
		(29 "B.CrtYd" user "Package Geometry/Place Bound Bottom")
		(35 "F.Fab" user "Ref Des/Assembly Top")
		(33 "B.Fab" user "Ref Des/Assembly Bottom")
	)
	(footprint ""
		(layer "F.Cu")
		(at 6.449822 -352.669856)
		(property "Reference" "J25"
			(at 6.653784 1.81356 90)
			(unlocked yes)
			(layer "F.SilkS")
			(effects
				(font
					(size 0.7874 0.5842)
					(thickness 0.1524)
				)
				(justify left)
			)
		)
		(property "Value" ""
			(at 0 0 0)
			(layer "F.Fab")
			(effects
				(font
					(size 1.27 1.27)
				)
			)
		)
		(duplicate_pad_numbers_are_jumpers no)
		(pad "" np_thru_hole circle
			(at -1.249934 11.649964 270)
			(size 2.413 2.413)
			(drill 2.413)
			(layers "*.Cu" "*.Mask")
			(clearance 0.381)
			(thermal_gap 0.381)
		)
		(pad "" np_thru_hole circle
			(at -1.249934 84.799932 270)
			(size 2.413 2.413)
			(drill 2.413)
			(layers "*.Cu" "*.Mask")
			(clearance 0.381)
			(thermal_gap 0.381)
		)
		(pad "A1" thru_hole rect
			(at 0 0 270)
			(size 1.016 1.016)
			(drill 0.7112)
			(layers "*.Cu" "*.Mask")
			(remove_unused_layers no)
			(net "MATE_A1")
			(clearance 0.1016)
			(thermal_gap 0.1016)
			(padstack
				(mode front_inner_back)
				(layer "Inner"
					(shape circle)
					(size 1.016 1.016)
					(clearance 0.1016)
				)
				(layer "B.Cu"
					(shape rect)
					(size 1.016 1.016)
					(clearance 0.1016)
				)
			)
		)
		(pad "A2" thru_hole circle
			(at 1.999996 0.999998 270)
			(size 1.016 1.016)
			(drill 0.7112)
			(layers "*.Cu" "*.Mask")
			(remove_unused_layers no)
			(net "GND")
			(clearance 0.1016)
			(thermal_gap 0.1016)
		)
		(pad "A3" thru_hole circle
			(at 0 1.999996 270)
			(size 1.016 1.016)
			(drill 0.7112)
			(layers "*.Cu" "*.Mask")
			(remove_unused_layers no)
			(net "LAN2_P3_P")
			(clearance 0.1016)
			(thermal_gap 0.1016)
		)
		(pad "A4" thru_hole circle
			(at 1.999996 2.999994 270)
			(size 1.016 1.016)
			(drill 0.7112)
			(layers "*.Cu" "*.Mask")
			(remove_unused_layers no)
			(net "LAN2_P3_N")
			(clearance 0.1016)
			(thermal_gap 0.1016)
		)
		(pad "A5" thru_hole circle
			(at 0 3.999992 270)
			(size 1.016 1.016)
			(drill 0.7112)
			(layers "*.Cu" "*.Mask")
			(remove_unused_layers no)
			(net "GND")
			(clearance 0.1016)
			(thermal_gap 0.1016)
		)
		(pad "A6" thru_hole circle
			(at 1.999996 4.99999 270)
			(size 1.016 1.016)
			(drill 0.7112)
			(layers "*.Cu" "*.Mask")
			(remove_unused_layers no)
			(net "LAN2_P4_P")
			(clearance 0.1016)
			(thermal_gap 0.1016)
		)
		(pad "A7" thru_hole circle
			(at 0 5.999988 270)
			(size 1.016 1.016)
			(drill 0.7112)
			(layers "*.Cu" "*.Mask")
			(remove_unused_layers no)
			(net "LAN2_P4_N")
			(clearance 0.1016)
			(thermal_gap 0.1016)
		)
		(pad "A8" thru_hole circle
			(at 1.999996 6.999986 270)
			(size 1.016 1.016)
			(drill 0.7112)
			(layers "*.Cu" "*.Mask")
			(remove_unused_layers no)
			(net "GND")
			(clearance 0.1016)
			(thermal_gap 0.1016)
		)
		(pad "A9" thru_hole circle
			(at 0 7.999984 270)
			(size 1.016 1.016)
			(drill 0.7112)
			(layers "*.Cu" "*.Mask")
			(remove_unused_layers no)
			(net "POWER_SW3_PWR_CTR_12V")
			(clearance 0.1016)
			(thermal_gap 0.1016)
		)
		(pad "A10" thru_hole circle
			(at 1.999996 8.999982 270)
			(size 1.016 1.016)
			(drill 0.7112)
			(layers "*.Cu" "*.Mask")
			(remove_unused_layers no)
			(net "POWER_SW2_PWR_CTR_12V")
			(clearance 0.1016)
			(thermal_gap 0.1016)
		)
		(pad "A11" thru_hole circle
			(at 0 9.99998 270)
			(size 1.016 1.016)
			(drill 0.7112)
			(layers "*.Cu" "*.Mask")
			(remove_unused_layers no)
			(net "POWER_SW1_PWR_CTR_12V")
			(clearance 0.1016)
			(thermal_gap 0.1016)
		)
		(pad "A12" thru_hole circle
			(at 1.999996 12.999974 270)
			(size 1.016 1.016)
			(drill 0.7112)
			(layers "*.Cu" "*.Mask")
			(remove_unused_layers no)
			(net "GND36")
			(clearance 0.1016)
			(thermal_gap 0.1016)
		)
		(pad "A13" thru_hole circle
			(at 0 13.999972 270)
			(size 1.016 1.016)
			(drill 0.7112)
			(layers "*.Cu" "*.Mask")
			(remove_unused_layers no)
			(net "Net_417")
			(clearance 0.1016)
			(thermal_gap 0.1016)
		)
		(pad "A14" thru_hole circle
			(at 1.999996 14.99997 270)
			(size 1.016 1.016)
			(drill 0.7112)
			(layers "*.Cu" "*.Mask")
			(remove_unused_layers no)
			(net "Net_416")
			(clearance 0.1016)
			(thermal_gap 0.1016)
		)
		(pad "A15" thru_hole circle
			(at 0 15.999968 270)
			(size 1.016 1.016)
			(drill 0.7112)
			(layers "*.Cu" "*.Mask")
			(remove_unused_layers no)
			(net "GND37")
			(clearance 0.1016)
			(thermal_gap 0.1016)
		)
		(pad "A16" thru_hole circle
			(at 1.999996 16.999966 270)
			(size 1.016 1.016)
			(drill 0.7112)
			(layers "*.Cu" "*.Mask")
			(remove_unused_layers no)
			(net "Net_421")
			(clearance 0.1016)
			(thermal_gap 0.1016)
		)
		(pad "A17" thru_hole circle
			(at 0 17.999964 270)
			(size 1.016 1.016)
			(drill 0.7112)
			(layers "*.Cu" "*.Mask")
			(remove_unused_layers no)
			(net "GND")
			(clearance 0.1016)
			(thermal_gap 0.1016)
		)
		(pad "A18" thru_hole circle
			(at 1.999996 18.999962 270)
			(size 1.016 1.016)
			(drill 0.7112)
			(layers "*.Cu" "*.Mask")
			(remove_unused_layers no)
			(net "UART_RTS_RP6_L_N")
			(clearance 0.1016)
			(thermal_gap 0.1016)
		)
		(pad "A19" thru_hole circle
			(at 0 19.99996 270)
			(size 1.016 1.016)
			(drill 0.7112)
			(layers "*.Cu" "*.Mask")
			(remove_unused_layers no)
			(net "UART_DSR_RP6_L")
			(clearance 0.1016)
			(thermal_gap 0.1016)
		)
		(pad "A20" thru_hole circle
			(at 1.999996 20.999958 270)
			(size 1.016 1.016)
			(drill 0.7112)
			(layers "*.Cu" "*.Mask")
			(remove_unused_layers no)
			(net "UART_RX_RP6_L")
			(clearance 0.1016)
			(thermal_gap 0.1016)
		)
		(pad "A21" thru_hole circle
			(at 0 21.999956 270)
			(size 1.016 1.016)
			(drill 0.7112)
			(layers "*.Cu" "*.Mask")
			(remove_unused_layers no)
			(net "UART_TX_RP6_L")
			(clearance 0.1016)
			(thermal_gap 0.1016)
		)
		(pad "A22" thru_hole circle
			(at 1.999996 22.999954 270)
			(size 1.016 1.016)
			(drill 0.7112)
			(layers "*.Cu" "*.Mask")
			(remove_unused_layers no)
			(net "UART_DTR_RP6_L_N")
			(clearance 0.1016)
			(thermal_gap 0.1016)
		)
		(pad "A23" thru_hole circle
			(at 0 23.999952 270)
			(size 1.016 1.016)
			(drill 0.7112)
			(layers "*.Cu" "*.Mask")
			(remove_unused_layers no)
			(net "UART_CTS_RP6_L_N")
			(clearance 0.1016)
			(thermal_gap 0.1016)
		)
		(pad "A24" thru_hole circle
			(at 1.999996 24.99995 270)
			(size 1.016 1.016)
			(drill 0.7112)
			(layers "*.Cu" "*.Mask")
			(remove_unused_layers no)
			(net "UART_RI_RP6_L_N")
			(clearance 0.1016)
			(thermal_gap 0.1016)
		)
		(pad "A25" thru_hole circle
			(at 0 25.999948 270)
			(size 1.016 1.016)
			(drill 0.7112)
			(layers "*.Cu" "*.Mask")
			(remove_unused_layers no)
			(net "GND")
			(clearance 0.1016)
			(thermal_gap 0.1016)
		)
		(pad "A26" thru_hole circle
			(at 1.999996 26.999946 270)
			(size 1.016 1.016)
			(drill 0.7112)
			(layers "*.Cu" "*.Mask")
			(remove_unused_layers no)
			(net "FAN4_TACH")
			(clearance 0.1016)
			(thermal_gap 0.1016)
		)
		(pad "A27" thru_hole circle
			(at 0 27.999944 270)
			(size 1.016 1.016)
			(drill 0.7112)
			(layers "*.Cu" "*.Mask")
			(remove_unused_layers no)
			(net "FAN5_TACH")
			(clearance 0.1016)
			(thermal_gap 0.1016)
		)
		(pad "A28" thru_hole circle
			(at 1.999996 28.999942 270)
			(size 1.016 1.016)
			(drill 0.7112)
			(layers "*.Cu" "*.Mask")
			(remove_unused_layers no)
			(net "FAN6_TACH")
			(clearance 0.1016)
			(thermal_gap 0.1016)
		)
		(pad "A29" thru_hole circle
			(at 0 29.99994 270)
			(size 1.016 1.016)
			(drill 0.7112)
			(layers "*.Cu" "*.Mask")
			(remove_unused_layers no)
			(net "GND")
			(clearance 0.1016)
			(thermal_gap 0.1016)
		)
		(pad "A30" thru_hole circle
			(at 1.999996 30.999938 270)
			(size 1.016 1.016)
			(drill 0.7112)
			(layers "*.Cu" "*.Mask")
			(remove_unused_layers no)
			(net "FAN_PWM")
			(clearance 0.1016)
			(thermal_gap 0.1016)
		)
		(pad "A31" thru_hole circle
			(at 0 31.999936 270)
			(size 1.016 1.016)
			(drill 0.7112)
			(layers "*.Cu" "*.Mask")
			(remove_unused_layers no)
			(net "GND")
			(clearance 0.1016)
			(thermal_gap 0.1016)
		)
		(pad "A32" thru_hole circle
			(at 1.999996 32.999934 270)
			(size 1.016 1.016)
			(drill 0.7112)
			(layers "*.Cu" "*.Mask")
			(remove_unused_layers no)
			(net "I2C_PSU3_SCL")
			(clearance 0.1016)
			(thermal_gap 0.1016)
		)
		(pad "A33" thru_hole circle
			(at 0 33.999932 270)
			(size 1.016 1.016)
			(drill 0.7112)
			(layers "*.Cu" "*.Mask")
			(remove_unused_layers no)
			(net "I2C_PSU3_SDA")
			(clearance 0.1016)
			(thermal_gap 0.1016)
		)
		(pad "A34" thru_hole circle
			(at 1.999996 34.99993 270)
			(size 1.016 1.016)
			(drill 0.7112)
			(layers "*.Cu" "*.Mask")
			(remove_unused_layers no)
			(net "GND")
			(clearance 0.1016)
			(thermal_gap 0.1016)
		)
		(pad "A35" thru_hole circle
			(at 0 35.999928 270)
			(size 1.016 1.016)
			(drill 0.7112)
			(layers "*.Cu" "*.Mask")
			(remove_unused_layers no)
			(net "T11_BLAD1_EN")
			(clearance 0.1016)
			(thermal_gap 0.1016)
		)
		(pad "A36" thru_hole circle
			(at 1.999996 36.999926 270)
			(size 1.016 1.016)
			(drill 0.7112)
			(layers "*.Cu" "*.Mask")
			(remove_unused_layers no)
			(net "T11_BLAD2_EN")
			(clearance 0.1016)
			(thermal_gap 0.1016)
		)
		(pad "A37" thru_hole circle
			(at 0 37.999924 270)
			(size 1.016 1.016)
			(drill 0.7112)
			(layers "*.Cu" "*.Mask")
			(remove_unused_layers no)
			(net "T11_BLAD3_EN")
			(clearance 0.1016)
			(thermal_gap 0.1016)
		)
		(pad "A38" thru_hole circle
			(at 1.999996 38.999922 270)
			(size 1.016 1.016)
			(drill 0.7112)
			(layers "*.Cu" "*.Mask")
			(remove_unused_layers no)
			(net "T11_BLAD4_EN")
			(clearance 0.1016)
			(thermal_gap 0.1016)
		)
		(pad "A39" thru_hole circle
			(at 0 39.99992 270)
			(size 1.016 1.016)
			(drill 0.7112)
			(layers "*.Cu" "*.Mask")
			(remove_unused_layers no)
			(net "GND")
			(clearance 0.1016)
			(thermal_gap 0.1016)
		)
		(pad "A40" thru_hole circle
			(at 1.999996 40.999918 270)
			(size 1.016 1.016)
			(drill 0.7112)
			(layers "*.Cu" "*.Mask")
			(remove_unused_layers no)
			(net "T11_BLAD1_RXD")
			(clearance 0.1016)
			(thermal_gap 0.1016)
		)
		(pad "A41" thru_hole circle
			(at 0 41.999916 270)
			(size 1.016 1.016)
			(drill 0.7112)
			(layers "*.Cu" "*.Mask")
			(remove_unused_layers no)
			(net "T11_BLAD1_TXD")
			(clearance 0.1016)
			(thermal_gap 0.1016)
		)
		(pad "A42" thru_hole circle
			(at 1.999996 42.999914 270)
			(size 1.016 1.016)
			(drill 0.7112)
			(layers "*.Cu" "*.Mask")
			(remove_unused_layers no)
			(net "T11_BLAD2_RXD")
			(clearance 0.1016)
			(thermal_gap 0.1016)
		)
		(pad "A43" thru_hole circle
			(at 0 43.999912 270)
			(size 1.016 1.016)
			(drill 0.7112)
			(layers "*.Cu" "*.Mask")
			(remove_unused_layers no)
			(net "T11_BLAD2_TXD")
			(clearance 0.1016)
			(thermal_gap 0.1016)
		)
		(pad "A44" thru_hole circle
			(at 1.999996 44.99991 270)
			(size 1.016 1.016)
			(drill 0.7112)
			(layers "*.Cu" "*.Mask")
			(remove_unused_layers no)
			(net "GND")
			(clearance 0.1016)
			(thermal_gap 0.1016)
		)
		(pad "A45" thru_hole circle
			(at 0 45.999908 270)
			(size 1.016 1.016)
			(drill 0.7112)
			(layers "*.Cu" "*.Mask")
			(remove_unused_layers no)
			(net "T11_BLAD3_RXD")
			(clearance 0.1016)
			(thermal_gap 0.1016)
		)
		(pad "A46" thru_hole circle
			(at 1.999996 46.999906 270)
			(size 1.016 1.016)
			(drill 0.7112)
			(layers "*.Cu" "*.Mask")
			(remove_unused_layers no)
			(net "T11_BLAD3_TXD")
			(clearance 0.1016)
			(thermal_gap 0.1016)
		)
		(pad "A47" thru_hole circle
			(at 0 47.999904 270)
			(size 1.016 1.016)
			(drill 0.7112)
			(layers "*.Cu" "*.Mask")
			(remove_unused_layers no)
			(net "T11_BLAD4_RXD")
			(clearance 0.1016)
			(thermal_gap 0.1016)
		)
		(pad "A48" thru_hole circle
			(at 1.999996 48.999902 270)
			(size 1.016 1.016)
			(drill 0.7112)
			(layers "*.Cu" "*.Mask")
			(remove_unused_layers no)
			(net "T11_BLAD4_TXD")
			(clearance 0.1016)
			(thermal_gap 0.1016)
		)
		(pad "A49" thru_hole circle
			(at 0 49.9999 270)
			(size 1.016 1.016)
			(drill 0.7112)
			(layers "*.Cu" "*.Mask")
			(remove_unused_layers no)
			(net "GND")
			(clearance 0.1016)
			(thermal_gap 0.1016)
		)
		(pad "A50" thru_hole circle
			(at 1.999996 50.999898 270)
			(size 1.016 1.016)
			(drill 0.7112)
			(layers "*.Cu" "*.Mask")
			(remove_unused_layers no)
			(net "T9_BLAD1_EN")
			(clearance 0.1016)
			(thermal_gap 0.1016)
		)
		(pad "A51" thru_hole circle
			(at 0 51.999896 270)
			(size 1.016 1.016)
			(drill 0.7112)
			(layers "*.Cu" "*.Mask")
			(remove_unused_layers no)
			(net "T9_BLAD2_EN")
			(clearance 0.1016)
			(thermal_gap 0.1016)
		)
		(pad "A52" thru_hole circle
			(at 1.999996 52.999894 270)
			(size 1.016 1.016)
			(drill 0.7112)
			(layers "*.Cu" "*.Mask")
			(remove_unused_layers no)
			(net "T9_BLAD3_EN")
			(clearance 0.1016)
			(thermal_gap 0.1016)
		)
		(pad "A53" thru_hole circle
			(at 0 53.999892 270)
			(size 1.016 1.016)
			(drill 0.7112)
			(layers "*.Cu" "*.Mask")
			(remove_unused_layers no)
			(net "T9_BLAD4_EN")
			(clearance 0.1016)
			(thermal_gap 0.1016)
		)
		(pad "A54" thru_hole circle
			(at 1.999996 54.99989 270)
			(size 1.016 1.016)
			(drill 0.7112)
			(layers "*.Cu" "*.Mask")
			(remove_unused_layers no)
			(net "GND")
			(clearance 0.1016)
			(thermal_gap 0.1016)
		)
		(pad "A55" thru_hole circle
			(at 0 55.999888 270)
			(size 1.016 1.016)
			(drill 0.7112)
			(layers "*.Cu" "*.Mask")
			(remove_unused_layers no)
			(net "T9_BLAD1_RXD")
			(clearance 0.1016)
			(thermal_gap 0.1016)
		)
		(pad "A56" thru_hole circle
			(at 1.999996 56.999886 270)
			(size 1.016 1.016)
			(drill 0.7112)
			(layers "*.Cu" "*.Mask")
			(remove_unused_layers no)
			(net "T9_BLAD1_TXD")
			(clearance 0.1016)
			(thermal_gap 0.1016)
		)
		(pad "A57" thru_hole circle
			(at 0 57.999884 270)
			(size 1.016 1.016)
			(drill 0.7112)
			(layers "*.Cu" "*.Mask")
			(remove_unused_layers no)
			(net "T9_BLAD2_RXD")
			(clearance 0.1016)
			(thermal_gap 0.1016)
		)
		(pad "A58" thru_hole circle
			(at 1.999996 59.000136 270)
			(size 1.016 1.016)
			(drill 0.7112)
			(layers "*.Cu" "*.Mask")
			(remove_unused_layers no)
			(net "T9_BLAD2_TXD")
			(clearance 0.1016)
			(thermal_gap 0.1016)
		)
		(pad "A59" thru_hole circle
			(at 0 59.99988 270)
			(size 1.016 1.016)
			(drill 0.7112)
			(layers "*.Cu" "*.Mask")
			(remove_unused_layers no)
			(net "GND")
			(clearance 0.1016)
			(thermal_gap 0.1016)
		)
		(pad "A60" thru_hole circle
			(at 1.999996 61.000132 270)
			(size 1.016 1.016)
			(drill 0.7112)
			(layers "*.Cu" "*.Mask")
			(remove_unused_layers no)
			(net "T9_BLAD3_RXD")
			(clearance 0.1016)
			(thermal_gap 0.1016)
		)
		(pad "A61" thru_hole circle
			(at 0 61.999876 270)
			(size 1.016 1.016)
			(drill 0.7112)
			(layers "*.Cu" "*.Mask")
			(remove_unused_layers no)
			(net "T9_BLAD3_TXD")
			(clearance 0.1016)
			(thermal_gap 0.1016)
		)
		(pad "A62" thru_hole circle
			(at 1.999996 63.000128 270)
			(size 1.016 1.016)
			(drill 0.7112)
			(layers "*.Cu" "*.Mask")
			(remove_unused_layers no)
			(net "T9_BLAD4_RXD")
			(clearance 0.1016)
			(thermal_gap 0.1016)
		)
		(pad "A63" thru_hole circle
			(at 0 63.999872 270)
			(size 1.016 1.016)
			(drill 0.7112)
			(layers "*.Cu" "*.Mask")
			(remove_unused_layers no)
			(net "T9_BLAD4_TXD")
			(clearance 0.1016)
			(thermal_gap 0.1016)
		)
		(pad "A64" thru_hole circle
			(at 1.999996 65.000124 270)
			(size 1.016 1.016)
			(drill 0.7112)
			(layers "*.Cu" "*.Mask")
			(remove_unused_layers no)
			(net "GND")
			(clearance 0.1016)
			(thermal_gap 0.1016)
		)
		(pad "A65" thru_hole circle
			(at 0 65.999868 270)
			(size 1.016 1.016)
			(drill 0.7112)
			(layers "*.Cu" "*.Mask")
			(remove_unused_layers no)
			(net "T7_BLAD1_EN")
			(clearance 0.1016)
			(thermal_gap 0.1016)
		)
		(pad "A66" thru_hole circle
			(at 1.999996 67.00012 270)
			(size 1.016 1.016)
			(drill 0.7112)
			(layers "*.Cu" "*.Mask")
			(remove_unused_layers no)
			(net "T7_BLAD2_EN")
			(clearance 0.1016)
			(thermal_gap 0.1016)
		)
		(pad "A67" thru_hole circle
			(at 0 67.999864 270)
			(size 1.016 1.016)
			(drill 0.7112)
			(layers "*.Cu" "*.Mask")
			(remove_unused_layers no)
			(net "T7_BLAD3_EN")
			(clearance 0.1016)
			(thermal_gap 0.1016)
		)
		(pad "A68" thru_hole circle
			(at 1.999996 69.000116 270)
			(size 1.016 1.016)
			(drill 0.7112)
			(layers "*.Cu" "*.Mask")
			(remove_unused_layers no)
			(net "T7_BLAD4_EN")
			(clearance 0.1016)
			(thermal_gap 0.1016)
		)
		(pad "A69" thru_hole circle
			(at 0 70.000114 270)
			(size 1.016 1.016)
			(drill 0.7112)
			(layers "*.Cu" "*.Mask")
			(remove_unused_layers no)
			(net "GND")
			(clearance 0.1016)
			(thermal_gap 0.1016)
		)
		(pad "A70" thru_hole circle
			(at 1.999996 71.000112 270)
			(size 1.016 1.016)
			(drill 0.7112)
			(layers "*.Cu" "*.Mask")
			(remove_unused_layers no)
			(net "T7_BLAD1_RXD")
			(clearance 0.1016)
			(thermal_gap 0.1016)
		)
		(pad "A71" thru_hole circle
			(at 0 72.00011 270)
			(size 1.016 1.016)
			(drill 0.7112)
			(layers "*.Cu" "*.Mask")
			(remove_unused_layers no)
			(net "T7_BLAD1_TXD")
			(clearance 0.1016)
			(thermal_gap 0.1016)
		)
		(pad "A72" thru_hole circle
			(at 1.999996 73.000108 270)
			(size 1.016 1.016)
			(drill 0.7112)
			(layers "*.Cu" "*.Mask")
			(remove_unused_layers no)
			(net "T7_BLAD2_RXD")
			(clearance 0.1016)
			(thermal_gap 0.1016)
		)
		(pad "A73" thru_hole circle
			(at 0 74.000106 270)
			(size 1.016 1.016)
			(drill 0.7112)
			(layers "*.Cu" "*.Mask")
			(remove_unused_layers no)
			(net "T7_BLAD2_TXD")
			(clearance 0.1016)
			(thermal_gap 0.1016)
		)
		(pad "A74" thru_hole circle
			(at 1.999996 75.000104 270)
			(size 1.016 1.016)
			(drill 0.7112)
			(layers "*.Cu" "*.Mask")
			(remove_unused_layers no)
			(net "GND")
			(clearance 0.1016)
			(thermal_gap 0.1016)
		)
		(pad "A75" thru_hole circle
			(at 0 76.000102 270)
			(size 1.016 1.016)
			(drill 0.7112)
			(layers "*.Cu" "*.Mask")
			(remove_unused_layers no)
			(net "T7_BLAD3_RXD")
			(clearance 0.1016)
			(thermal_gap 0.1016)
		)
		(pad "A76" thru_hole circle
			(at 1.999996 77.0001 270)
			(size 1.016 1.016)
			(drill 0.7112)
			(layers "*.Cu" "*.Mask")
			(remove_unused_layers no)
			(net "T7_BLAD3_TXD")
			(clearance 0.1016)
			(thermal_gap 0.1016)
		)
	)
)
